# BASEBOARD_FAB2 (Tioga Pass) — schematic netlist excerpt (pin names and nets, part order shuffled) for the footprints in the layout excerpt that follows; sources: Cadence DE-HDL packaged netlist, KiCad conversion of Wiwynn_Tioga_Pass_MB.brd

R9F23  RES  20.0 1% CHIP  pkg 0402  page 160 : A = SMB_LAN_STBY_LVC3_SDA_R ; B = SMB_LAN_STBY_LVC3_SDA
C4U2  CAP  10UF 4V 20% X6S  pkg 0603LF  page 231 : A = PVPP_ABC ; B = GND
C5G50  CAP_A  22.0UF 4V 20% X6S  pkg 0603V  page 242 : A = PVDDQ_ABC ; B = GND

(kicad_pcb
	(version 20260206)
	(generator "pcbnew")
	(generator_version "10.0")
	(general
		(thickness 1.6)
		(legacy_teardrops no)
	)
	(paper "A4")
	(title_block
		(title "Wiwynn_Tioga_Pass_MB.brd")
		(comment 1 "Tioga Pass / footprints 3753-3755 of 4770")
	)
	(layers
		(0 "F.Cu" signal "TOP")
		(4 "In1.Cu" signal "L2GND")
		(6 "In2.Cu" signal "L3")
		(8 "In3.Cu" signal "L4GND")
		(10 "In4.Cu" signal "L5")
		(12 "In5.Cu" signal "L6GND")
		(14 "In6.Cu" signal "L7VCC")
		(16 "In7.Cu" signal "L8VCC")
		(18 "In8.Cu" signal "L9GND")
		(20 "In9.Cu" signal "L10")
		(22 "In10.Cu" signal "L11GND")
		(24 "In11.Cu" signal "L12")
		(26 "In12.Cu" signal "L13GND")
		(2 "B.Cu" signal "BOTTOM")
		(9 "F.Adhes" user "F.Adhesive")
		(11 "B.Adhes" user "B.Adhesive")
		(13 "F.Paste" user "Package Geometry/Pastemask Top")
		(15 "B.Paste" user "Package Geometry/Pastemask Bottom")
		(5 "F.SilkS" user "Ref Des/Silkscreen Top")
		(7 "B.SilkS" user "Ref Des/Silkscreen Bottom")
		(1 "F.Mask" user "Board Geometry/Soldermask Top")
		(3 "B.Mask" user "Board Geometry/Soldermask Bottom")
		(17 "Dwgs.User" user "User.Drawings")
		(19 "Cmts.User" user "User.Comments")
		(21 "Eco1.User" user "User.Eco1")
		(23 "Eco2.User" user "User.Eco2")
		(25 "Edge.Cuts" user "Board Geometry/Outline")
		(27 "Margin" user)
		(31 "F.CrtYd" user "Package Geometry/Place Bound Top")
		(29 "B.CrtYd" user "Package Geometry/Place Bound Bottom")
		(35 "F.Fab" user "Ref Des/Assembly Top")
		(33 "B.Fab" user "Ref Des/Assembly Bottom")
	)
	(footprint ""
		(layer "B.Cu")
		(at 318.543432 -8.128 -90)
		(property "Reference" "C4U2"
			(at 0 0 90)
			(layer "B.SilkS")
			(hide yes)
			(effects
				(font
					(size 1.27 1.27)
				)
				(justify mirror)
			)
		)
		(property "Value" ""
			(at 0 0 90)
			(layer "B.Fab")
			(effects
				(font
					(size 1.27 1.27)
				)
				(justify mirror)
			)
		)
		(duplicate_pad_numbers_are_jumpers no)
		(fp_poly
			(pts
				(xy 0.4953 -0.2032) (xy -0.4953 -0.2032) (xy -0.4953 1.6002) (xy 0.4953 1.6002)
			)
			(stroke
				(width 0)
				(type default)
			)
			(fill no)
			(layer "B.CrtYd")
		)
		(fp_line
			(start -0.4953 1.6002)
			(end 0.4953 1.6002)
			(stroke
				(width 0.1)
				(type default)
			)
			(layer "B.Fab")
		)
		(fp_line
			(start 0.4953 1.6002)
			(end 0.4953 -0.2032)
			(stroke
				(width 0.1)
				(type default)
			)
			(layer "B.Fab")
		)
		(fp_line
			(start -0.4953 -0.2032)
			(end -0.4953 1.6002)
			(stroke
				(width 0.1)
				(type default)
			)
			(layer "B.Fab")
		)
		(fp_line
			(start 0.4953 -0.2032)
			(end -0.4953 -0.2032)
			(stroke
				(width 0.1)
				(type default)
			)
			(layer "B.Fab")
		)
		(pad "1" smd rect
			(at 0 0 90)
			(size 0.762 0.889)
			(layers "B.Cu" "B.Mask" "B.Paste")
			(net "PVPP_ABC")
		)
		(pad "2" smd rect
			(at 0 1.397 90)
			(size 0.762 0.889)
			(layers "B.Cu" "B.Mask" "B.Paste")
			(net "GND")
		)
		(zone
			(layer "B.Cu")
			(hatch none 0.5)
			(connect_pads
				(clearance 0)
			)
			(min_thickness 0.25)
			(keepout
				(tracks not_allowed)
				(vias allowed)
				(pads allowed)
				(copperpour not_allowed)
				(footprints allowed)
			)
			(placement
				(enabled no)
				(sheetname "")
			)
			(fill
				(thermal_gap 0.5)
				(thermal_bridge_width 0.5)
				(island_removal_mode 0)
			)
			(polygon
				(pts
					(xy 318.098932 -7.747) (xy 318.098932 -8.509) (xy 317.590932 -8.509) (xy 317.590932 -7.747)
				)
			)
		)
	)
	(footprint ""
		(layer "B.Cu")
		(at 416.470846 -44.650152 180)
		(property "Reference" "R9F23"
			(at 0 0 0)
			(layer "B.SilkS")
			(hide yes)
			(effects
				(font
					(size 1.27 1.27)
				)
				(justify mirror)
			)
		)
		(property "Value" ""
			(at 0 0 0)
			(layer "B.Fab")
			(effects
				(font
					(size 1.27 1.27)
				)
				(justify mirror)
			)
		)
		(duplicate_pad_numbers_are_jumpers no)
		(fp_poly
			(pts
				(xy 0.2794 -0.1016) (xy -0.2794 -0.1016) (xy -0.2794 0.9906) (xy 0.2794 0.9906)
			)
			(stroke
				(width 0)
				(type default)
			)
			(fill no)
			(layer "B.CrtYd")
		)
		(fp_line
			(start 0.2794 0.9906)
			(end -0.2794 0.9906)
			(stroke
				(width 0.1)
				(type default)
			)
			(layer "B.Fab")
		)
		(fp_line
			(start 0.2794 -0.1016)
			(end 0.2794 0.9906)
			(stroke
				(width 0.1)
				(type default)
			)
			(layer "B.Fab")
		)
		(fp_line
			(start -0.2794 0.9906)
			(end -0.2794 -0.1016)
			(stroke
				(width 0.1)
				(type default)
			)
			(layer "B.Fab")
		)
		(fp_line
			(start -0.2794 -0.1016)
			(end 0.2794 -0.1016)
			(stroke
				(width 0.1)
				(type default)
			)
			(layer "B.Fab")
		)
		(pad "1" smd rect
			(at 0 0)
			(size 0.508 0.508)
			(layers "B.Cu" "B.Mask" "B.Paste")
			(net "SMB_LAN_STBY_LVC3_SDA_R")
		)
		(pad "2" smd rect
			(at 0 0.889)
			(size 0.508 0.508)
			(layers "B.Cu" "B.Mask" "B.Paste")
			(net "SMB_LAN_STBY_LVC3_SDA")
		)
		(zone
			(layer "B.Cu")
			(hatch none 0.5)
			(connect_pads
				(clearance 0)
			)
			(min_thickness 0.25)
			(keepout
				(tracks not_allowed)
				(vias allowed)
				(pads allowed)
				(copperpour not_allowed)
				(footprints allowed)
			)
			(placement
				(enabled no)
				(sheetname "")
			)
			(fill
				(thermal_gap 0.5)
				(thermal_bridge_width 0.5)
				(island_removal_mode 0)
			)
			(polygon
				(pts
					(xy 416.216846 -45.285152) (xy 416.724846 -45.285152) (xy 416.724846 -44.904152) (xy 416.216846 -44.904152)
				)
			)
		)
		(zone
			(layer "B.Cu")
			(hatch none 0.5)
			(connect_pads
				(clearance 0)
			)
			(min_thickness 0.25)
			(keepout
				(tracks allowed)
				(vias not_allowed)
				(pads allowed)
				(copperpour not_allowed)
				(footprints allowed)
			)
			(placement
				(enabled no)
				(sheetname "")
			)
			(fill
				(thermal_gap 0.5)
				(thermal_bridge_width 0.5)
				(island_removal_mode 0)
			)
			(polygon
				(pts
					(xy 416.216846 -44.904152) (xy 416.724846 -44.904152) (xy 416.724846 -45.285152) (xy 416.216846 -45.285152)
				)
			)
		)
	)
	(footprint ""
		(layer "B.Cu")
		(at 245.7323 -3.3528 -90)
		(property "Reference" "C5G50"
			(at -1.14681 0.76708 0)
			(unlocked yes)
			(layer "B.SilkS")
			(effects
				(font
					(size 0.7874 0.5842)
					(thickness 0.1524)
				)
				(justify mirror)
			)
		)
		(property "Value" ""
			(at 0 0 90)
			(layer "B.Fab")
			(effects
				(font
					(size 1.27 1.27)
				)
				(justify mirror)
			)
		)
		(duplicate_pad_numbers_are_jumpers no)
		(fp_rect
			(start 0.4953 1.6002)
			(end -0.4953 -0.2032)
			(stroke
				(width 0)
				(type default)
			)
			(fill no)
			(layer "B.CrtYd")
		)
		(fp_line
			(start -0.4953 1.6002)
			(end 0.4953 1.6002)
			(stroke
				(width 0.1)
				(type default)
			)
			(layer "B.Fab")
		)
		(fp_line
			(start 0.4953 1.6002)
			(end 0.4953 -0.2032)
			(stroke
				(width 0.1)
				(type default)
			)
			(layer "B.Fab")
		)
		(fp_line
			(start -0.4953 -0.2032)
			(end -0.4953 1.6002)
			(stroke
				(width 0.1)
				(type default)
			)
			(layer "B.Fab")
		)
		(fp_line
			(start 0.4953 -0.2032)
			(end -0.4953 -0.2032)
			(stroke
				(width 0.1)
				(type default)
			)
			(layer "B.Fab")
		)
		(pad "1" smd rect
			(at 0 0 90)
			(size 0.762 0.889)
			(layers "B.Cu" "B.Mask" "B.Paste")
			(net "PVDDQ_ABC")
		)
		(pad "2" smd rect
			(at 0 1.397 90)
			(size 0.762 0.889)
			(layers "B.Cu" "B.Mask" "B.Paste")
			(net "GND")
		)
		(zone
			(layer "B.Cu")
			(hatch none 0.5)
			(connect_pads
				(clearance 0)
			)
			(min_thickness 0.25)
			(keepout
				(tracks not_allowed)
				(vias allowed)
				(pads allowed)
				(copperpour not_allowed)
				(footprints allowed)
			)
			(placement
				(enabled no)
				(sheetname "")
			)
			(fill
				(thermal_gap 0.5)
				(thermal_bridge_width 0.5)
				(island_removal_mode 0)
			)
			(polygon
				(pts
					(xy 244.7798 -2.9718) (xy 245.2878 -2.9718) (xy 245.2878 -3.7338) (xy 244.7798 -3.7338)
				)
			)
		)
	)
)
